# T6G (Grand Teton) — schematic netlist excerpt (pin names and nets, part order shuffled) for the footprints in the layout excerpt that follows; sources: Cadence DE-HDL packaged netlist, KiCad conversion of 04192023_DAF0TMB3IC0_F0TG_MB_C_brd_V02_OCP.brd

C2237  Q_CAP  22UF 4V 20% X6S  pkg C0402  page 69 : A = PVDDCR_CPU1_P0 ; B = GND
R1268  Q_RES  4.7K 1% EMPTY  pkg 0402LF  page 258 : A = ADC128_2_VREF ; B = GND
PC350_3  Q_CAP  22UF 16V 20% X6S  pkg C0805  page 216 : A = SW_P12V_AUX_PVDDCR_SOC_P1_FLT ; B = GND

(kicad_pcb
	(version 20260206)
	(generator "pcbnew")
	(generator_version "10.0")
	(general
		(thickness 1.6)
		(legacy_teardrops no)
	)
	(paper "A4")
	(title_block
		(title "04192023_DAF0TMB3IC0_F0TG_MB_C_brd_V02_OCP.brd")
		(comment 1 "Grand Teton / footprints 7588-7590 of 8354")
	)
	(layers
		(0 "F.Cu" signal "TOP")
		(4 "In1.Cu" signal "GND")
		(6 "In2.Cu" signal "IN1")
		(8 "In3.Cu" signal "GND1")
		(10 "In4.Cu" signal "IN2")
		(12 "In5.Cu" signal "GND2")
		(14 "In6.Cu" signal "IN3")
		(16 "In7.Cu" signal "GND3")
		(18 "In8.Cu" signal "VCC")
		(20 "In9.Cu" signal "VCC1")
		(22 "In10.Cu" signal "GND4")
		(24 "In11.Cu" signal "IN4")
		(26 "In12.Cu" signal "GND5")
		(28 "In13.Cu" signal "IN5")
		(30 "In14.Cu" signal "GND6")
		(32 "In15.Cu" signal "IN6")
		(34 "In16.Cu" signal "GND7")
		(2 "B.Cu" signal "BOTTOM")
		(9 "F.Adhes" user "F.Adhesive")
		(11 "B.Adhes" user "B.Adhesive")
		(13 "F.Paste" user "Package Geometry/Pastemask Top")
		(15 "B.Paste" user "Package Geometry/Pastemask Bottom")
		(5 "F.SilkS" user "Ref Des/Silkscreen Top")
		(7 "B.SilkS" user "Ref Des/Silkscreen Bottom")
		(1 "F.Mask" user "Board Geometry/Soldermask Top")
		(3 "B.Mask" user "Board Geometry/Soldermask Bottom")
		(17 "Dwgs.User" user "User.Drawings")
		(19 "Cmts.User" user "User.Comments")
		(21 "Eco1.User" user "User.Eco1")
		(23 "Eco2.User" user "User.Eco2")
		(25 "Edge.Cuts" user "Board Geometry/Outline")
		(27 "Margin" user)
		(31 "F.CrtYd" user "Package Geometry/Place Bound Top")
		(29 "B.CrtYd" user "Package Geometry/Place Bound Bottom")
		(35 "F.Fab" user "Ref Des/Assembly Top")
		(33 "B.Fab" user "Ref Des/Assembly Bottom")
	)
	(footprint ""
		(layer "B.Cu")
		(at 216.0905 -322.52539)
		(property "Reference" "R1268"
			(at 0 0 0)
			(layer "B.SilkS")
			(hide yes)
			(effects
				(font
					(size 1.27 1.27)
				)
				(justify mirror)
			)
		)
		(property "Value" ""
			(at 0 0 0)
			(layer "B.Fab")
			(effects
				(font
					(size 1.27 1.27)
				)
				(justify mirror)
			)
		)
		(duplicate_pad_numbers_are_jumpers no)
		(fp_line
			(start -0.7874 -0.4064)
			(end -0.7874 0.4064)
			(stroke
				(width 0.1524)
				(type default)
			)
			(layer "B.SilkS")
		)
		(fp_line
			(start -0.7874 0.4064)
			(end 0.7874 0.4064)
			(stroke
				(width 0.1524)
				(type default)
			)
			(layer "B.SilkS")
		)
		(fp_line
			(start 0.7874 -0.4064)
			(end -0.7874 -0.4064)
			(stroke
				(width 0.1524)
				(type default)
			)
			(layer "B.SilkS")
		)
		(fp_line
			(start 0.7874 0.4064)
			(end 0.7874 -0.4064)
			(stroke
				(width 0.1524)
				(type default)
			)
			(layer "B.SilkS")
		)
		(fp_line
			(start -0.67945 -0.3048)
			(end -0.67945 0.3048)
			(stroke
				(width 0.1)
				(type default)
			)
			(layer "B.Fab")
		)
		(fp_line
			(start -0.67945 0.3048)
			(end -0.120396 0.3048)
			(stroke
				(width 0.1)
				(type default)
			)
			(layer "B.Fab")
		)
		(fp_line
			(start -0.12065 -0.3048)
			(end -0.67945 -0.3048)
			(stroke
				(width 0.1)
				(type default)
			)
			(layer "B.Fab")
		)
		(fp_line
			(start -0.12065 -0.2794)
			(end -0.12065 -0.3048)
			(stroke
				(width 0.1)
				(type default)
			)
			(layer "B.Fab")
		)
		(fp_line
			(start -0.120396 0.2794)
			(end 0.12065 0.2794)
			(stroke
				(width 0.1)
				(type default)
			)
			(layer "B.Fab")
		)
		(fp_line
			(start -0.120396 0.3048)
			(end -0.120396 0.2794)
			(stroke
				(width 0.1)
				(type default)
			)
			(layer "B.Fab")
		)
		(fp_line
			(start 0.12065 -0.305054)
			(end 0.12065 -0.2794)
			(stroke
				(width 0.1)
				(type default)
			)
			(layer "B.Fab")
		)
		(fp_line
			(start 0.12065 -0.2794)
			(end -0.12065 -0.2794)
			(stroke
				(width 0.1)
				(type default)
			)
			(layer "B.Fab")
		)
		(fp_line
			(start 0.12065 0.2794)
			(end 0.12065 0.3048)
			(stroke
				(width 0.1)
				(type default)
			)
			(layer "B.Fab")
		)
		(fp_line
			(start 0.12065 0.3048)
			(end 0.67945 0.3048)
			(stroke
				(width 0.1)
				(type default)
			)
			(layer "B.Fab")
		)
		(fp_line
			(start 0.67945 -0.305054)
			(end 0.12065 -0.305054)
			(stroke
				(width 0.1)
				(type default)
			)
			(layer "B.Fab")
		)
		(fp_line
			(start 0.67945 0.3048)
			(end 0.67945 -0.305054)
			(stroke
				(width 0.1)
				(type default)
			)
			(layer "B.Fab")
		)
		(pad "1" smd circle
			(at 0.40005 0 180)
			(size 0 0)
			(layers "B.Cu" "B.Mask" "B.Paste")
			(net "ADC128_2_VREF")
		)
		(pad "2" smd circle
			(at -0.40005 0 180)
			(size 0 0)
			(layers "B.Cu" "B.Mask" "B.Paste")
			(net "GND")
		)
	)
	(footprint ""
		(layer "B.Cu")
		(at 131.321048 -156.393134 -90)
		(property "Reference" "PC350_3"
			(at 0 0 90)
			(layer "B.SilkS")
			(hide yes)
			(effects
				(font
					(size 1.27 1.27)
				)
				(justify mirror)
			)
		)
		(property "Value" ""
			(at 0 0 90)
			(layer "B.Fab")
			(effects
				(font
					(size 1.27 1.27)
				)
				(justify mirror)
			)
		)
		(duplicate_pad_numbers_are_jumpers no)
		(fp_line
			(start -1.524 0.762)
			(end 1.524 0.762)
			(stroke
				(width 0.1524)
				(type default)
			)
			(layer "B.SilkS")
		)
		(fp_line
			(start 1.524 0.762)
			(end 1.524 -0.762)
			(stroke
				(width 0.1524)
				(type default)
			)
			(layer "B.SilkS")
		)
		(fp_line
			(start -1.524 -0.762)
			(end -1.524 0.762)
			(stroke
				(width 0.1524)
				(type default)
			)
			(layer "B.SilkS")
		)
		(fp_line
			(start 1.524 -0.762)
			(end -1.524 -0.762)
			(stroke
				(width 0.1524)
				(type default)
			)
			(layer "B.SilkS")
		)
		(fp_line
			(start -1.1049 0.724916)
			(end -1.1049 -0.724916)
			(stroke
				(width 0.1)
				(type default)
			)
			(layer "B.Fab")
		)
		(fp_line
			(start 1.1049 0.724916)
			(end -1.1049 0.724916)
			(stroke
				(width 0.1)
				(type default)
			)
			(layer "B.Fab")
		)
		(fp_line
			(start -1.1049 -0.724916)
			(end 1.1049 -0.724916)
			(stroke
				(width 0.1)
				(type default)
			)
			(layer "B.Fab")
		)
		(fp_line
			(start 1.1049 -0.724916)
			(end 1.1049 0.724916)
			(stroke
				(width 0.1)
				(type default)
			)
			(layer "B.Fab")
		)
		(pad "1" smd rect
			(at 0.889 0 270)
			(size 1.016 1.27)
			(layers "B.Cu" "B.Mask" "B.Paste")
			(net "SW_P12V_AUX_PVDDCR_SOC_P1_FLT")
		)
		(pad "2" smd rect
			(at -0.889 0 270)
			(size 1.016 1.27)
			(layers "B.Cu" "B.Mask" "B.Paste")
			(net "GND")
		)
	)
	(footprint ""
		(layer "B.Cu")
		(at 352.501454 -267.52931)
		(property "Reference" "C2237"
			(at 0 0 0)
			(layer "B.SilkS")
			(hide yes)
			(effects
				(font
					(size 1.27 1.27)
				)
				(justify mirror)
			)
		)
		(property "Value" ""
			(at 0 0 0)
			(layer "B.Fab")
			(effects
				(font
					(size 1.27 1.27)
				)
				(justify mirror)
			)
		)
		(duplicate_pad_numbers_are_jumpers no)
		(fp_line
			(start -0.7874 -0.4064)
			(end -0.7874 0.4064)
			(stroke
				(width 0.1524)
				(type default)
			)
			(layer "B.SilkS")
		)
		(fp_line
			(start -0.7874 0.4064)
			(end 0.7874 0.4064)
			(stroke
				(width 0.1524)
				(type default)
			)
			(layer "B.SilkS")
		)
		(fp_line
			(start 0.7874 -0.4064)
			(end -0.7874 -0.4064)
			(stroke
				(width 0.1524)
				(type default)
			)
			(layer "B.SilkS")
		)
		(fp_line
			(start 0.7874 0.4064)
			(end 0.7874 -0.4064)
			(stroke
				(width 0.1524)
				(type default)
			)
			(layer "B.SilkS")
		)
		(fp_line
			(start -0.67945 -0.3048)
			(end -0.67945 0.3048)
			(stroke
				(width 0.1)
				(type default)
			)
			(layer "B.Fab")
		)
		(fp_line
			(start -0.67945 0.3048)
			(end -0.120396 0.3048)
			(stroke
				(width 0.1)
				(type default)
			)
			(layer "B.Fab")
		)
		(fp_line
			(start -0.12065 -0.3048)
			(end -0.67945 -0.3048)
			(stroke
				(width 0.1)
				(type default)
			)
			(layer "B.Fab")
		)
		(fp_line
			(start -0.12065 -0.2794)
			(end -0.12065 -0.3048)
			(stroke
				(width 0.1)
				(type default)
			)
			(layer "B.Fab")
		)
		(fp_line
			(start -0.120396 0.2794)
			(end 0.12065 0.2794)
			(stroke
				(width 0.1)
				(type default)
			)
			(layer "B.Fab")
		)
		(fp_line
			(start -0.120396 0.3048)
			(end -0.120396 0.2794)
			(stroke
				(width 0.1)
				(type default)
			)
			(layer "B.Fab")
		)
		(fp_line
			(start 0.12065 -0.305054)
			(end 0.12065 -0.2794)
			(stroke
				(width 0.1)
				(type default)
			)
			(layer "B.Fab")
		)
		(fp_line
			(start 0.12065 -0.2794)
			(end -0.12065 -0.2794)
			(stroke
				(width 0.1)
				(type default)
			)
			(layer "B.Fab")
		)
		(fp_line
			(start 0.12065 0.2794)
			(end 0.12065 0.3048)
			(stroke
				(width 0.1)
				(type default)
			)
			(layer "B.Fab")
		)
		(fp_line
			(start 0.12065 0.3048)
			(end 0.67945 0.3048)
			(stroke
				(width 0.1)
				(type default)
			)
			(layer "B.Fab")
		)
		(fp_line
			(start 0.67945 -0.305054)
			(end 0.12065 -0.305054)
			(stroke
				(width 0.1)
				(type default)
			)
			(layer "B.Fab")
		)
		(fp_line
			(start 0.67945 0.3048)
			(end 0.67945 -0.305054)
			(stroke
				(width 0.1)
				(type default)
			)
			(layer "B.Fab")
		)
		(pad "1" smd circle
			(at 0.40005 0 180)
			(size 0 0)
			(layers "B.Cu" "B.Mask" "B.Paste")
			(net "PVDDCR_CPU1_P0")
		)
		(pad "2" smd circle
			(at -0.40005 0 180)
			(size 0 0)
			(layers "B.Cu" "B.Mask" "B.Paste")
			(net "GND")
		)
	)
)
